(kicad_pcb
	(version 20260206)
	(generator "pcbnew")
	(generator_version "10.0")
	(general
		(thickness 1.6)
		(legacy_teardrops no)
	)
	(paper "A4")
	(title_block
		(title "baseboard — 13948-1b.1110WZS1818.brd")
		(comment 1 "Honey Badger (Wiwynn) / footprints 281-287 of 2523")
	)
	(layers
		(0 "F.Cu" signal "TOP")
		(4 "In1.Cu" signal "L2GND")
		(6 "In2.Cu" signal "L3")
		(8 "In3.Cu" signal "L4VCC")
		(10 "In4.Cu" signal "L5VCC")
		(12 "In5.Cu" signal "L6")
		(14 "In6.Cu" signal "L7GND")
		(2 "B.Cu" signal "BOTTOM")
		(9 "F.Adhes" user "F.Adhesive")
		(11 "B.Adhes" user "B.Adhesive")
		(13 "F.Paste" user "Package Geometry/Pastemask Top")
		(15 "B.Paste" user "Package Geometry/Pastemask Bottom")
		(5 "F.SilkS" user "Ref Des/Silkscreen Top")
		(7 "B.SilkS" user "Ref Des/Silkscreen Bottom")
		(1 "F.Mask" user "Board Geometry/Soldermask Top")
		(3 "B.Mask" user "Board Geometry/Soldermask Bottom")
		(17 "Dwgs.User" user "User.Drawings")
		(19 "Cmts.User" user "User.Comments")
		(21 "Eco1.User" user "User.Eco1")
		(23 "Eco2.User" user "User.Eco2")
		(25 "Edge.Cuts" user "Board Geometry/Outline")
		(27 "Margin" user)
		(31 "F.CrtYd" user "Package Geometry/Place Bound Top")
		(29 "B.CrtYd" user "Package Geometry/Place Bound Bottom")
		(35 "F.Fab" user "Ref Des/Assembly Top")
		(33 "B.Fab" user "Ref Des/Assembly Bottom")
	)
	(footprint ""
		(layer "F.Cu")
		(at 231.013 -14.478 180)
		(property "Reference" "Q9"
			(at 0 0 180)
			(layer "F.SilkS")
			(hide yes)
			(effects
				(font
					(size 1.27 1.27)
				)
			)
		)
		(property "Value" "2N7002A-7-GP"
			(at 0.127 -8.9662 180)
			(unlocked yes)
			(layer "F.Fab")
			(hide yes)
			(effects
				(font
					(size 1.016 1.016)
					(thickness 0.1524)
				)
			)
		)
		(property "Device Type" "SOT23DGS2D4H48"
			(at 0.127 -10.4902 180)
			(unlocked yes)
			(layer "F.Fab")
			(hide yes)
			(effects
				(font
					(size 1.016 1.016)
					(thickness 0.1524)
				)
			)
		)
		(duplicate_pad_numbers_are_jumpers no)
		(fp_line
			(start 1.651 1.778)
			(end 1.651 -1.778)
			(stroke
				(width 0.1524)
				(type default)
			)
			(layer "F.SilkS")
		)
		(fp_line
			(start 1.651 -1.778)
			(end -1.651 -1.778)
			(stroke
				(width 0.1524)
				(type default)
			)
			(layer "F.SilkS")
		)
		(fp_line
			(start -1.651 1.778)
			(end 1.651 1.778)
			(stroke
				(width 0.1524)
				(type default)
			)
			(layer "F.SilkS")
		)
		(fp_line
			(start -1.651 -1.778)
			(end -1.651 1.778)
			(stroke
				(width 0.1524)
				(type default)
			)
			(layer "F.SilkS")
		)
		(fp_poly
			(pts
				(xy -1.778 1.8796) (xy -1.778 -1.8796) (xy 1.778 -1.8796) (xy 1.778 1.8796)
			)
			(stroke
				(width 0)
				(type default)
			)
			(fill no)
			(layer "F.CrtYd")
		)
		(fp_poly
			(pts
				(xy -1.778 1.8796) (xy -1.778 -1.8796) (xy 1.778 -1.8796) (xy 1.778 1.8796)
			)
			(stroke
				(width 0)
				(type default)
			)
			(fill no)
			(layer "F.Fab")
		)
		(pad "D" smd custom
			(at 0 -0.9525 180)
			(size 0.1905 0.1905)
			(layers "F.Cu" "F.Mask" "F.Paste")
			(net "ENCLO_LED_RED_D")
			(options
				(clearance outline)
				(anchor circle)
			)
			(primitives
				(gr_poly
					(pts
						(arc
							(start -0.1778 0.5715)
							(mid -0.321484 0.511984)
							(end -0.381 0.3683)
						)
						(arc
							(start -0.381 -0.3683)
							(mid -0.321484 -0.511984)
							(end -0.1778 -0.5715)
						)
						(arc
							(start 0.1778 -0.5715)
							(mid 0.321484 -0.511984)
							(end 0.381 -0.3683)
						)
						(arc
							(start 0.381 0.3683)
							(mid 0.321484 0.511984)
							(end 0.1778 0.5715)
						)
					)
					(width 0)
					(fill yes)
				)
			)
		)
		(pad "G" smd custom
			(at -0.98425 0.9525 180)
			(size 0.1905 0.1905)
			(layers "F.Cu" "F.Mask" "F.Paste")
			(net "ENCLO_LED_RED_G")
			(options
				(clearance outline)
				(anchor circle)
			)
			(primitives
				(gr_poly
					(pts
						(arc
							(start -0.1778 0.5715)
							(mid -0.321484 0.511984)
							(end -0.381 0.3683)
						)
						(arc
							(start -0.381 -0.3683)
							(mid -0.321484 -0.511984)
							(end -0.1778 -0.5715)
						)
						(arc
							(start 0.1778 -0.5715)
							(mid 0.321484 -0.511984)
							(end 0.381 -0.3683)
						)
						(arc
							(start 0.381 0.3683)
							(mid 0.321484 0.511984)
							(end 0.1778 0.5715)
						)
					)
					(width 0)
					(fill yes)
				)
			)
		)
		(pad "S" smd custom
			(at 0.98425 0.9525 180)
			(size 0.1905 0.1905)
			(layers "F.Cu" "F.Mask" "F.Paste")
			(net "GND")
			(options
				(clearance outline)
				(anchor circle)
			)
			(primitives
				(gr_poly
					(pts
						(arc
							(start -0.1778 0.5715)
							(mid -0.321484 0.511984)
							(end -0.381 0.3683)
						)
						(arc
							(start -0.381 -0.3683)
							(mid -0.321484 -0.511984)
							(end -0.1778 -0.5715)
						)
						(arc
							(start 0.1778 -0.5715)
							(mid 0.321484 -0.511984)
							(end 0.381 -0.3683)
						)
						(arc
							(start 0.381 0.3683)
							(mid 0.321484 0.511984)
							(end 0.1778 0.5715)
						)
					)
					(width 0)
					(fill yes)
				)
			)
		)
	)
	(footprint ""
		(layer "F.Cu")
		(at 152.019 -56.642 -90)
		(property "Reference" "SR691"
			(at 0 0 270)
			(layer "F.SilkS")
			(hide yes)
			(effects
				(font
					(size 1.27 1.27)
				)
			)
		)
		(property "Value" "10KR2F-2-GP"
			(at 0.064008 -3.993896 270)
			(unlocked yes)
			(layer "F.Fab")
			(hide yes)
			(effects
				(font
					(size 1.016 1.016)
					(thickness 0.1524)
				)
			)
		)
		(property "Device Type" "R402H16"
			(at 0.064008 -5.517896 270)
			(unlocked yes)
			(layer "F.Fab")
			(hide yes)
			(effects
				(font
					(size 1.016 1.016)
					(thickness 0.1524)
				)
			)
		)
		(duplicate_pad_numbers_are_jumpers no)
		(fp_line
			(start -0.508 -0.9398)
			(end -0.508 0.9398)
			(stroke
				(width 0.1524)
				(type default)
			)
			(layer "F.SilkS")
		)
		(fp_line
			(start 0.508 -0.9398)
			(end -0.508 -0.9398)
			(stroke
				(width 0.1524)
				(type default)
			)
			(layer "F.SilkS")
		)
		(fp_rect
			(start -0.508 0.9398)
			(end 0.508 -0.9398)
			(stroke
				(width 0)
				(type default)
			)
			(fill no)
			(layer "F.CrtYd")
		)
		(fp_rect
			(start -0.508 0.9398)
			(end 0.508 -0.9398)
			(stroke
				(width 0)
				(type default)
			)
			(fill no)
			(layer "F.Fab")
		)
		(pad "1" smd custom
			(at 0 -0.4445 270)
			(size 0.1397 0.1397)
			(layers "F.Cu" "F.Mask" "F.Paste")
			(net "P1V8_C")
			(options
				(clearance outline)
				(anchor circle)
			)
			(primitives
				(gr_poly
					(pts
						(arc
							(start -0.1778 -0.2794)
							(mid -0.249642 -0.249642)
							(end -0.2794 -0.1778)
						)
						(arc
							(start -0.2794 0.1778)
							(mid -0.249642 0.249642)
							(end -0.1778 0.2794)
						)
						(arc
							(start 0.1778 0.2794)
							(mid 0.249642 0.249642)
							(end 0.2794 0.1778)
						)
						(arc
							(start 0.2794 -0.1778)
							(mid 0.249642 -0.249642)
							(end 0.1778 -0.2794)
						)
					)
					(width 0)
					(fill yes)
				)
			)
		)
		(pad "2" smd custom
			(at 0 0.4445 270)
			(size 0.1397 0.1397)
			(layers "F.Cu" "F.Mask" "F.Paste")
			(net "XM_ADDR_7")
			(options
				(clearance outline)
				(anchor circle)
			)
			(primitives
				(gr_poly
					(pts
						(arc
							(start -0.1778 -0.2794)
							(mid -0.249642 -0.249642)
							(end -0.2794 -0.1778)
						)
						(arc
							(start -0.2794 0.1778)
							(mid -0.249642 0.249642)
							(end -0.1778 0.2794)
						)
						(arc
							(start 0.1778 0.2794)
							(mid 0.249642 0.249642)
							(end 0.2794 0.1778)
						)
						(arc
							(start 0.2794 -0.1778)
							(mid 0.249642 -0.249642)
							(end 0.1778 -0.2794)
						)
					)
					(width 0)
					(fill yes)
				)
			)
		)
	)
	(footprint ""
		(layer "F.Cu")
		(at 173.49597 -67.183)
		(property "Reference" "C292"
			(at 0 0 0)
			(layer "F.SilkS")
			(hide yes)
			(effects
				(font
					(size 1.27 1.27)
				)
			)
		)
		(property "Value" "SCD1U25V2KX-2-GP"
			(at 1.1811 -2.7051 0)
			(unlocked yes)
			(layer "F.Fab")
			(hide yes)
			(effects
				(font
					(size 1.016 1.016)
					(thickness 0.1524)
				)
			)
		)
		(property "Device Type" "C402H22"
			(at 1.1811 -4.2291 0)
			(unlocked yes)
			(layer "F.Fab")
			(hide yes)
			(effects
				(font
					(size 1.016 1.016)
					(thickness 0.1524)
				)
			)
		)
		(duplicate_pad_numbers_are_jumpers no)
		(fp_rect
			(start -0.4318 0.9525)
			(end 0.4318 -0.9525)
			(stroke
				(width 0)
				(type default)
			)
			(fill no)
			(layer "F.CrtYd")
		)
		(fp_rect
			(start -0.4318 0.9525)
			(end 0.4318 -0.9525)
			(stroke
				(width 0)
				(type default)
			)
			(fill no)
			(layer "F.Fab")
		)
		(pad "1" smd custom
			(at 0 -0.4445)
			(size 0.1524 0.1524)
			(layers "F.Cu" "F.Mask" "F.Paste")
			(net "TP_MSB_A46_GBE_RX_N")
			(options
				(clearance outline)
				(anchor circle)
			)
			(primitives
				(gr_poly
					(pts
						(arc
							(start 0.3048 -0.2032)
							(mid 0.275042 -0.275042)
							(end 0.2032 -0.3048)
						)
						(arc
							(start -0.2032 -0.3048)
							(mid -0.275042 -0.275042)
							(end -0.3048 -0.2032)
						)
						(arc
							(start -0.3048 0.2032)
							(mid -0.275042 0.275042)
							(end -0.2032 0.3048)
						)
						(arc
							(start 0.2032 0.3048)
							(mid 0.275042 0.275042)
							(end 0.3048 0.2032)
						)
					)
					(width 0)
					(fill yes)
				)
			)
		)
		(pad "2" smd custom
			(at 0 0.4445)
			(size 0.1524 0.1524)
			(layers "F.Cu" "F.Mask" "F.Paste")
			(net "GND")
			(options
				(clearance outline)
				(anchor circle)
			)
			(primitives
				(gr_poly
					(pts
						(arc
							(start 0.3048 -0.2032)
							(mid 0.275042 -0.275042)
							(end 0.2032 -0.3048)
						)
						(arc
							(start -0.2032 -0.3048)
							(mid -0.275042 -0.275042)
							(end -0.3048 -0.2032)
						)
						(arc
							(start -0.3048 0.2032)
							(mid -0.275042 0.275042)
							(end -0.2032 0.3048)
						)
						(arc
							(start 0.2032 0.3048)
							(mid 0.275042 0.275042)
							(end 0.3048 0.2032)
						)
					)
					(width 0)
					(fill yes)
				)
			)
		)
	)
	(footprint ""
		(layer "F.Cu")
		(at 317.290958 -62.357 -90)
		(property "Reference" "R255"
			(at 0 0 270)
			(layer "F.SilkS")
			(hide yes)
			(effects
				(font
					(size 1.27 1.27)
				)
			)
		)
		(property "Value" "0R2J-2-GP"
			(at 0.064008 -3.993896 270)
			(unlocked yes)
			(layer "F.Fab")
			(hide yes)
			(effects
				(font
					(size 1.016 1.016)
					(thickness 0.1524)
				)
			)
		)
		(property "Device Type" "R402H16"
			(at 0.064008 -5.517896 270)
			(unlocked yes)
			(layer "F.Fab")
			(hide yes)
			(effects
				(font
					(size 1.016 1.016)
					(thickness 0.1524)
				)
			)
		)
		(duplicate_pad_numbers_are_jumpers no)
		(fp_line
			(start -0.508 -0.9398)
			(end -0.508 0.9398)
			(stroke
				(width 0.1524)
				(type default)
			)
			(layer "F.SilkS")
		)
		(fp_line
			(start 0.508 -0.9398)
			(end -0.508 -0.9398)
			(stroke
				(width 0.1524)
				(type default)
			)
			(layer "F.SilkS")
		)
		(fp_rect
			(start -0.508 0.9398)
			(end 0.508 -0.9398)
			(stroke
				(width 0)
				(type default)
			)
			(fill no)
			(layer "F.CrtYd")
		)
		(fp_rect
			(start -0.508 0.9398)
			(end 0.508 -0.9398)
			(stroke
				(width 0)
				(type default)
			)
			(fill no)
			(layer "F.Fab")
		)
		(pad "1" smd custom
			(at 0 -0.4445 270)
			(size 0.1397 0.1397)
			(layers "F.Cu" "F.Mask" "F.Paste")
			(net "BMC_MBC_I2C_E_SDA")
			(options
				(clearance outline)
				(anchor circle)
			)
			(primitives
				(gr_poly
					(pts
						(arc
							(start -0.1778 -0.2794)
							(mid -0.249642 -0.249642)
							(end -0.2794 -0.1778)
						)
						(arc
							(start -0.2794 0.1778)
							(mid -0.249642 0.249642)
							(end -0.1778 0.2794)
						)
						(arc
							(start 0.1778 0.2794)
							(mid 0.249642 0.249642)
							(end 0.2794 0.1778)
						)
						(arc
							(start 0.2794 -0.1778)
							(mid 0.249642 -0.249642)
							(end 0.1778 -0.2794)
						)
					)
					(width 0)
					(fill yes)
				)
			)
		)
		(pad "2" smd custom
			(at 0 0.4445 270)
			(size 0.1397 0.1397)
			(layers "F.Cu" "F.Mask" "F.Paste")
			(net "I2C_BMC_MSB_DATA_R")
			(options
				(clearance outline)
				(anchor circle)
			)
			(primitives
				(gr_poly
					(pts
						(arc
							(start -0.1778 -0.2794)
							(mid -0.249642 -0.249642)
							(end -0.2794 -0.1778)
						)
						(arc
							(start -0.2794 0.1778)
							(mid -0.249642 0.249642)
							(end -0.1778 0.2794)
						)
						(arc
							(start 0.1778 0.2794)
							(mid 0.249642 0.249642)
							(end 0.2794 0.1778)
						)
						(arc
							(start 0.2794 -0.1778)
							(mid 0.249642 -0.249642)
							(end 0.1778 -0.2794)
						)
					)
					(width 0)
					(fill yes)
				)
			)
		)
	)
	(footprint ""
		(layer "F.Cu")
		(at 17.214088 -202.185016)
		(property "Reference" "SR580"
			(at 0 0 0)
			(layer "F.SilkS")
			(hide yes)
			(effects
				(font
					(size 1.27 1.27)
				)
			)
		)
		(property "Value" "200KR2F-L-GP"
			(at 0.064008 -3.993896 0)
			(unlocked yes)
			(layer "F.Fab")
			(hide yes)
			(effects
				(font
					(size 1.016 1.016)
					(thickness 0.1524)
				)
			)
		)
		(property "Device Type" "R402H16"
			(at 0.064008 -5.517896 0)
			(unlocked yes)
			(layer "F.Fab")
			(hide yes)
			(effects
				(font
					(size 1.016 1.016)
					(thickness 0.1524)
				)
			)
		)
		(duplicate_pad_numbers_are_jumpers no)
		(fp_line
			(start -0.508 -0.9398)
			(end -0.508 0.9398)
			(stroke
				(width 0.1524)
				(type default)
			)
			(layer "F.SilkS")
		)
		(fp_line
			(start 0.508 -0.9398)
			(end -0.508 -0.9398)
			(stroke
				(width 0.1524)
				(type default)
			)
			(layer "F.SilkS")
		)
		(fp_rect
			(start -0.508 0.9398)
			(end 0.508 -0.9398)
			(stroke
				(width 0)
				(type default)
			)
			(fill no)
			(layer "F.CrtYd")
		)
		(fp_rect
			(start -0.508 0.9398)
			(end 0.508 -0.9398)
			(stroke
				(width 0)
				(type default)
			)
			(fill no)
			(layer "F.Fab")
		)
		(pad "1" smd custom
			(at 0 -0.4445)
			(size 0.1397 0.1397)
			(layers "F.Cu" "F.Mask" "F.Paste")
			(net "BMC_I2C10_EN")
			(options
				(clearance outline)
				(anchor circle)
			)
			(primitives
				(gr_poly
					(pts
						(arc
							(start -0.1778 -0.2794)
							(mid -0.249642 -0.249642)
							(end -0.2794 -0.1778)
						)
						(arc
							(start -0.2794 0.1778)
							(mid -0.249642 0.249642)
							(end -0.1778 0.2794)
						)
						(arc
							(start 0.1778 0.2794)
							(mid 0.249642 0.249642)
							(end 0.2794 0.1778)
						)
						(arc
							(start 0.2794 -0.1778)
							(mid 0.249642 -0.249642)
							(end 0.1778 -0.2794)
						)
					)
					(width 0)
					(fill yes)
				)
			)
		)
		(pad "2" smd custom
			(at 0 0.4445)
			(size 0.1397 0.1397)
			(layers "F.Cu" "F.Mask" "F.Paste")
			(net "P3V3_STBY")
			(options
				(clearance outline)
				(anchor circle)
			)
			(primitives
				(gr_poly
					(pts
						(arc
							(start -0.1778 -0.2794)
							(mid -0.249642 -0.249642)
							(end -0.2794 -0.1778)
						)
						(arc
							(start -0.2794 0.1778)
							(mid -0.249642 0.249642)
							(end -0.1778 0.2794)
						)
						(arc
							(start 0.1778 0.2794)
							(mid 0.249642 0.249642)
							(end 0.2794 0.1778)
						)
						(arc
							(start 0.2794 -0.1778)
							(mid 0.249642 -0.249642)
							(end 0.1778 -0.2794)
						)
					)
					(width 0)
					(fill yes)
				)
			)
		)
	)
	(footprint ""
		(layer "F.Cu")
		(at 112.973612 -205.867 180)
		(property "Reference" "SR879"
			(at 0 0 180)
			(layer "F.SilkS")
			(hide yes)
			(effects
				(font
					(size 1.27 1.27)
				)
			)
		)
		(property "Value" "0R2J-2-GP"
			(at 0.064008 -3.993896 180)
			(unlocked yes)
			(layer "F.Fab")
			(hide yes)
			(effects
				(font
					(size 1.016 1.016)
					(thickness 0.1524)
				)
			)
		)
		(property "Device Type" "R402H16"
			(at 0.064008 -5.517896 180)
			(unlocked yes)
			(layer "F.Fab")
			(hide yes)
			(effects
				(font
					(size 1.016 1.016)
					(thickness 0.1524)
				)
			)
		)
		(duplicate_pad_numbers_are_jumpers no)
		(fp_line
			(start 0.508 -0.9398)
			(end -0.508 -0.9398)
			(stroke
				(width 0.1524)
				(type default)
			)
			(layer "F.SilkS")
		)
		(fp_line
			(start -0.508 -0.9398)
			(end -0.508 0.9398)
			(stroke
				(width 0.1524)
				(type default)
			)
			(layer "F.SilkS")
		)
		(fp_rect
			(start -0.508 0.9398)
			(end 0.508 -0.9398)
			(stroke
				(width 0)
				(type default)
			)
			(fill no)
			(layer "F.CrtYd")
		)
		(fp_rect
			(start -0.508 0.9398)
			(end 0.508 -0.9398)
			(stroke
				(width 0)
				(type default)
			)
			(fill no)
			(layer "F.Fab")
		)
		(pad "1" smd custom
			(at 0 -0.4445 180)
			(size 0.1397 0.1397)
			(layers "F.Cu" "F.Mask" "F.Paste")
			(net "SAS_HDD_REDV_TX8_P")
			(options
				(clearance outline)
				(anchor circle)
			)
			(primitives
				(gr_poly
					(pts
						(arc
							(start -0.1778 -0.2794)
							(mid -0.249642 -0.249642)
							(end -0.2794 -0.1778)
						)
						(arc
							(start -0.2794 0.1778)
							(mid -0.249642 0.249642)
							(end -0.1778 0.2794)
						)
						(arc
							(start 0.1778 0.2794)
							(mid 0.249642 0.249642)
							(end 0.2794 0.1778)
						)
						(arc
							(start 0.2794 -0.1778)
							(mid 0.249642 -0.249642)
							(end 0.1778 -0.2794)
						)
					)
					(width 0)
					(fill yes)
				)
			)
		)
		(pad "2" smd custom
			(at 0 0.4445 180)
			(size 0.1397 0.1397)
			(layers "F.Cu" "F.Mask" "F.Paste")
			(net "REDV_TX8_P")
			(options
				(clearance outline)
				(anchor circle)
			)
			(primitives
				(gr_poly
					(pts
						(arc
							(start -0.1778 -0.2794)
							(mid -0.249642 -0.249642)
							(end -0.2794 -0.1778)
						)
						(arc
							(start -0.2794 0.1778)
							(mid -0.249642 0.249642)
							(end -0.1778 0.2794)
						)
						(arc
							(start 0.1778 0.2794)
							(mid 0.249642 0.249642)
							(end 0.2794 0.1778)
						)
						(arc
							(start 0.2794 -0.1778)
							(mid 0.249642 -0.249642)
							(end 0.1778 -0.2794)
						)
					)
					(width 0)
					(fill yes)
				)
			)
		)
	)
	(footprint ""
		(layer "F.Cu")
		(at 98.171 -60.325)
		(property "Reference" "STP38"
			(at 0 0 0)
			(layer "F.SilkS")
			(hide yes)
			(effects
				(font
					(size 1.27 1.27)
				)
			)
		)
		(property "Value" "TPAD28"
			(at 0.0127 -1.8034 0)
			(unlocked yes)
			(layer "F.Fab")
			(hide yes)
			(effects
				(font
					(size 1.016 1.016)
					(thickness 0.1524)
				)
			)
		)
		(property "Device Type" "TPAD28"
			(at 0.0127 -3.3274 0)
			(unlocked yes)
			(layer "F.Fab")
			(hide yes)
			(effects
				(font
					(size 1.016 1.016)
					(thickness 0.1524)
				)
			)
		)
		(duplicate_pad_numbers_are_jumpers no)
		(fp_poly
			(pts
				(arc
					(start 0.3556 0)
					(mid -0.3556 0)
					(end 0.3556 0)
				)
			)
			(stroke
				(width 0)
				(type default)
			)
			(fill no)
			(layer "F.CrtYd")
		)
		(fp_poly
			(pts
				(arc
					(start 0.6096 0)
					(mid -0.6096 0)
					(end 0.6096 0)
				)
			)
			(stroke
				(width 0)
				(type default)
			)
			(fill no)
			(layer "F.Fab")
		)
		(pad "1" smd circle
			(at 0 0)
			(size 0.7112 0.7112)
			(layers "F.Cu" "F.Mask" "F.Paste")
			(net "ICE1_TDO")
		)
	)
)
